# S9S_MB_2U (Grand Teton) — schematic netlist excerpt (pin names and nets, part order shuffled) for the footprints in the layout excerpt that follows; sources: Cadence DE-HDL packaged netlist, KiCad conversion of 03242023_DA0F0TMBIJ0_F0T_Motherboard_J_brd_V01_OCP.brd

R4120  Q_RES  100K 1% EMPTY  pkg 0402LF  page 146 : A = GPU_3V3IO_RSVD0_FFU ; B = GND
C1302  Q_CAP  22UF 4V 20% X6S  pkg C0402  page 240 : A = PVNN_TERM_CPU0 ; B = GND

(kicad_pcb
	(version 20260206)
	(generator "pcbnew")
	(generator_version "10.0")
	(general
		(thickness 1.6)
		(legacy_teardrops no)
	)
	(paper "A4")
	(title_block
		(title "03242023_DA0F0TMBIJ0_F0T_Motherboard_J_brd_V01_OCP.brd")
		(comment 1 "Grand Teton / footprints 945-946 of 6105")
	)
	(layers
		(0 "F.Cu" signal "TOP")
		(4 "In1.Cu" signal "GND")
		(6 "In2.Cu" signal "IN1")
		(8 "In3.Cu" signal "GND1")
		(10 "In4.Cu" signal "IN2")
		(12 "In5.Cu" signal "GND2")
		(14 "In6.Cu" signal "IN3")
		(16 "In7.Cu" signal "GND3")
		(18 "In8.Cu" signal "VCC")
		(20 "In9.Cu" signal "VCC1")
		(22 "In10.Cu" signal "GND4")
		(24 "In11.Cu" signal "IN4")
		(26 "In12.Cu" signal "GND5")
		(28 "In13.Cu" signal "IN5")
		(30 "In14.Cu" signal "GND6")
		(32 "In15.Cu" signal "IN6")
		(34 "In16.Cu" signal "GND7")
		(2 "B.Cu" signal "BOTTOM")
		(9 "F.Adhes" user "F.Adhesive")
		(11 "B.Adhes" user "B.Adhesive")
		(13 "F.Paste" user "Package Geometry/Pastemask Top")
		(15 "B.Paste" user "Package Geometry/Pastemask Bottom")
		(5 "F.SilkS" user "Ref Des/Silkscreen Top")
		(7 "B.SilkS" user "Ref Des/Silkscreen Bottom")
		(1 "F.Mask" user "Board Geometry/Soldermask Top")
		(3 "B.Mask" user "Board Geometry/Soldermask Bottom")
		(17 "Dwgs.User" user "User.Drawings")
		(19 "Cmts.User" user "User.Comments")
		(21 "Eco1.User" user "User.Eco1")
		(23 "Eco2.User" user "User.Eco2")
		(25 "Edge.Cuts" user "Board Geometry/Outline")
		(27 "Margin" user)
		(31 "F.CrtYd" user "Package Geometry/Place Bound Top")
		(29 "B.CrtYd" user "Package Geometry/Place Bound Bottom")
		(35 "F.Fab" user "Ref Des/Assembly Top")
		(33 "B.Fab" user "Ref Des/Assembly Bottom")
	)
	(footprint ""
		(layer "F.Cu")
		(at 302.895 -419.10635 -90)
		(property "Reference" "R4120"
			(at 0 0 270)
			(layer "F.SilkS")
			(hide yes)
			(effects
				(font
					(size 1.27 1.27)
				)
			)
		)
		(property "Value" ""
			(at 0 0 270)
			(layer "F.Fab")
			(effects
				(font
					(size 1.27 1.27)
				)
			)
		)
		(duplicate_pad_numbers_are_jumpers no)
		(fp_line
			(start -0.7874 0.4064)
			(end -0.7874 -0.4064)
			(stroke
				(width 0.1524)
				(type default)
			)
			(layer "F.SilkS")
		)
		(fp_line
			(start 0.7874 0.4064)
			(end -0.7874 0.4064)
			(stroke
				(width 0.1524)
				(type default)
			)
			(layer "F.SilkS")
		)
		(fp_line
			(start -0.7874 -0.4064)
			(end 0.7874 -0.4064)
			(stroke
				(width 0.1524)
				(type default)
			)
			(layer "F.SilkS")
		)
		(fp_line
			(start 0.7874 -0.4064)
			(end 0.7874 0.4064)
			(stroke
				(width 0.1524)
				(type default)
			)
			(layer "F.SilkS")
		)
		(fp_line
			(start -0.67945 0.3048)
			(end -0.67945 -0.305054)
			(stroke
				(width 0.1)
				(type default)
			)
			(layer "F.Fab")
		)
		(fp_line
			(start -0.12065 0.3048)
			(end -0.67945 0.3048)
			(stroke
				(width 0.1)
				(type default)
			)
			(layer "F.Fab")
		)
		(fp_line
			(start 0.120396 0.3048)
			(end 0.120396 0.2794)
			(stroke
				(width 0.1)
				(type default)
			)
			(layer "F.Fab")
		)
		(fp_line
			(start 0.67945 0.3048)
			(end 0.120396 0.3048)
			(stroke
				(width 0.1)
				(type default)
			)
			(layer "F.Fab")
		)
		(fp_line
			(start -0.12065 0.2794)
			(end -0.12065 0.3048)
			(stroke
				(width 0.1)
				(type default)
			)
			(layer "F.Fab")
		)
		(fp_line
			(start 0.120396 0.2794)
			(end -0.12065 0.2794)
			(stroke
				(width 0.1)
				(type default)
			)
			(layer "F.Fab")
		)
		(fp_line
			(start -0.12065 -0.2794)
			(end 0.12065 -0.2794)
			(stroke
				(width 0.1)
				(type default)
			)
			(layer "F.Fab")
		)
		(fp_line
			(start 0.12065 -0.2794)
			(end 0.12065 -0.3048)
			(stroke
				(width 0.1)
				(type default)
			)
			(layer "F.Fab")
		)
		(fp_line
			(start 0.12065 -0.3048)
			(end 0.67945 -0.3048)
			(stroke
				(width 0.1)
				(type default)
			)
			(layer "F.Fab")
		)
		(fp_line
			(start 0.67945 -0.3048)
			(end 0.67945 0.3048)
			(stroke
				(width 0.1)
				(type default)
			)
			(layer "F.Fab")
		)
		(fp_line
			(start -0.67945 -0.305054)
			(end -0.12065 -0.305054)
			(stroke
				(width 0.1)
				(type default)
			)
			(layer "F.Fab")
		)
		(fp_line
			(start -0.12065 -0.305054)
			(end -0.12065 -0.2794)
			(stroke
				(width 0.1)
				(type default)
			)
			(layer "F.Fab")
		)
		(pad "1" smd circle
			(at -0.40005 0 270)
			(size 0 0)
			(layers "F.Cu" "F.Mask" "F.Paste")
			(net "GPU_3V3IO_RSVD0_FFU")
		)
		(pad "2" smd circle
			(at 0.40005 0 270)
			(size 0 0)
			(layers "F.Cu" "F.Mask" "F.Paste")
			(net "GND")
		)
	)
	(footprint ""
		(layer "F.Cu")
		(at 164.592 -23.713948)
		(property "Reference" "C1302"
			(at 0 0 0)
			(layer "F.SilkS")
			(hide yes)
			(effects
				(font
					(size 1.27 1.27)
				)
			)
		)
		(property "Value" ""
			(at 0 0 0)
			(layer "F.Fab")
			(effects
				(font
					(size 1.27 1.27)
				)
			)
		)
		(duplicate_pad_numbers_are_jumpers no)
		(fp_line
			(start -0.7874 -0.4064)
			(end 0.7874 -0.4064)
			(stroke
				(width 0.1524)
				(type default)
			)
			(layer "F.SilkS")
		)
		(fp_line
			(start -0.7874 0.4064)
			(end -0.7874 -0.4064)
			(stroke
				(width 0.1524)
				(type default)
			)
			(layer "F.SilkS")
		)
		(fp_line
			(start 0.7874 -0.4064)
			(end 0.7874 0.4064)
			(stroke
				(width 0.1524)
				(type default)
			)
			(layer "F.SilkS")
		)
		(fp_line
			(start 0.7874 0.4064)
			(end -0.7874 0.4064)
			(stroke
				(width 0.1524)
				(type default)
			)
			(layer "F.SilkS")
		)
		(fp_line
			(start -0.67945 -0.305054)
			(end -0.12065 -0.305054)
			(stroke
				(width 0.1)
				(type default)
			)
			(layer "F.Fab")
		)
		(fp_line
			(start -0.67945 0.3048)
			(end -0.67945 -0.305054)
			(stroke
				(width 0.1)
				(type default)
			)
			(layer "F.Fab")
		)
		(fp_line
			(start -0.12065 -0.305054)
			(end -0.12065 -0.2794)
			(stroke
				(width 0.1)
				(type default)
			)
			(layer "F.Fab")
		)
		(fp_line
			(start -0.12065 -0.2794)
			(end 0.12065 -0.2794)
			(stroke
				(width 0.1)
				(type default)
			)
			(layer "F.Fab")
		)
		(fp_line
			(start -0.12065 0.2794)
			(end -0.12065 0.3048)
			(stroke
				(width 0.1)
				(type default)
			)
			(layer "F.Fab")
		)
		(fp_line
			(start -0.12065 0.3048)
			(end -0.67945 0.3048)
			(stroke
				(width 0.1)
				(type default)
			)
			(layer "F.Fab")
		)
		(fp_line
			(start 0.120396 0.2794)
			(end -0.12065 0.2794)
			(stroke
				(width 0.1)
				(type default)
			)
			(layer "F.Fab")
		)
		(fp_line
			(start 0.120396 0.3048)
			(end 0.120396 0.2794)
			(stroke
				(width 0.1)
				(type default)
			)
			(layer "F.Fab")
		)
		(fp_line
			(start 0.12065 -0.3048)
			(end 0.67945 -0.3048)
			(stroke
				(width 0.1)
				(type default)
			)
			(layer "F.Fab")
		)
		(fp_line
			(start 0.12065 -0.2794)
			(end 0.12065 -0.3048)
			(stroke
				(width 0.1)
				(type default)
			)
			(layer "F.Fab")
		)
		(fp_line
			(start 0.67945 -0.3048)
			(end 0.67945 0.3048)
			(stroke
				(width 0.1)
				(type default)
			)
			(layer "F.Fab")
		)
		(fp_line
			(start 0.67945 0.3048)
			(end 0.120396 0.3048)
			(stroke
				(width 0.1)
				(type default)
			)
			(layer "F.Fab")
		)
		(pad "1" smd circle
			(at -0.40005 0)
			(size 0 0)
			(layers "F.Cu" "F.Mask" "F.Paste")
			(net "PVNN_TERM_CPU0")
		)
		(pad "2" smd circle
			(at 0.40005 0)
			(size 0 0)
			(layers "F.Cu" "F.Mask" "F.Paste")
			(net "GND")
		)
	)
)
